(kicad_pcb
	(version 20260206)
	(generator "pcbnew")
	(generator_version "10.0")
	(general
		(thickness 1.6)
		(legacy_teardrops no)
	)
	(paper "A4")
	(title_block
		(title "01162023_DA0F0TEBIF0_F0T_Expander_BD_F_brd_V02_OCP.brd")
		(comment 1 "Grand Teton / footprints 1080-1086 of 9728")
	)
	(layers
		(0 "F.Cu" signal "TOP")
		(4 "In1.Cu" signal "GND")
		(6 "In2.Cu" signal "VCC")
		(8 "In3.Cu" signal "VCC1")
		(10 "In4.Cu" signal "GND1")
		(12 "In5.Cu" signal "IN1")
		(14 "In6.Cu" signal "GND2")
		(16 "In7.Cu" signal "IN2")
		(18 "In8.Cu" signal "GND3")
		(20 "In9.Cu" signal "IN3")
		(22 "In10.Cu" signal "GND4")
		(24 "In11.Cu" signal "IN4")
		(26 "In12.Cu" signal "GND5")
		(28 "In13.Cu" signal "IN5")
		(30 "In14.Cu" signal "GND6")
		(32 "In15.Cu" signal "IN6")
		(34 "In16.Cu" signal "GND7")
		(2 "B.Cu" signal "BOTTOM")
		(9 "F.Adhes" user "F.Adhesive")
		(11 "B.Adhes" user "B.Adhesive")
		(13 "F.Paste" user "Package Geometry/Pastemask Top")
		(15 "B.Paste" user "Package Geometry/Pastemask Bottom")
		(5 "F.SilkS" user "Ref Des/Silkscreen Top")
		(7 "B.SilkS" user "Ref Des/Silkscreen Bottom")
		(1 "F.Mask" user "Board Geometry/Soldermask Top")
		(3 "B.Mask" user "Board Geometry/Soldermask Bottom")
		(17 "Dwgs.User" user "User.Drawings")
		(19 "Cmts.User" user "User.Comments")
		(21 "Eco1.User" user "User.Eco1")
		(23 "Eco2.User" user "User.Eco2")
		(25 "Edge.Cuts" user "Board Geometry/Outline")
		(27 "Margin" user)
		(31 "F.CrtYd" user "Package Geometry/Place Bound Top")
		(29 "B.CrtYd" user "Package Geometry/Place Bound Bottom")
		(35 "F.Fab" user "Ref Des/Assembly Top")
		(33 "B.Fab" user "Ref Des/Assembly Bottom")
	)
	(footprint ""
		(layer "F.Cu")
		(at 198.120762 -370.348764 180)
		(property "Reference" "PC7"
			(at 0 0 180)
			(layer "F.SilkS")
			(hide yes)
			(effects
				(font
					(size 1.27 1.27)
				)
			)
		)
		(property "Value" ""
			(at 0 0 180)
			(layer "F.Fab")
			(effects
				(font
					(size 1.27 1.27)
				)
			)
		)
		(duplicate_pad_numbers_are_jumpers no)
		(fp_line
			(start 0.7874 0.4064)
			(end -0.7874 0.4064)
			(stroke
				(width 0.1524)
				(type default)
			)
			(layer "F.SilkS")
		)
		(fp_line
			(start 0.7874 -0.4064)
			(end 0.7874 0.4064)
			(stroke
				(width 0.1524)
				(type default)
			)
			(layer "F.SilkS")
		)
		(fp_line
			(start -0.7874 0.4064)
			(end -0.7874 -0.4064)
			(stroke
				(width 0.1524)
				(type default)
			)
			(layer "F.SilkS")
		)
		(fp_line
			(start -0.7874 -0.4064)
			(end 0.7874 -0.4064)
			(stroke
				(width 0.1524)
				(type default)
			)
			(layer "F.SilkS")
		)
		(fp_line
			(start 0.67945 0.3048)
			(end 0.120396 0.3048)
			(stroke
				(width 0.1)
				(type default)
			)
			(layer "F.Fab")
		)
		(fp_line
			(start 0.67945 -0.3048)
			(end 0.67945 0.3048)
			(stroke
				(width 0.1)
				(type default)
			)
			(layer "F.Fab")
		)
		(fp_line
			(start 0.12065 -0.2794)
			(end 0.12065 -0.3048)
			(stroke
				(width 0.1)
				(type default)
			)
			(layer "F.Fab")
		)
		(fp_line
			(start 0.12065 -0.3048)
			(end 0.67945 -0.3048)
			(stroke
				(width 0.1)
				(type default)
			)
			(layer "F.Fab")
		)
		(fp_line
			(start 0.120396 0.3048)
			(end 0.120396 0.2794)
			(stroke
				(width 0.1)
				(type default)
			)
			(layer "F.Fab")
		)
		(fp_line
			(start 0.120396 0.2794)
			(end -0.12065 0.2794)
			(stroke
				(width 0.1)
				(type default)
			)
			(layer "F.Fab")
		)
		(fp_line
			(start -0.12065 0.3048)
			(end -0.67945 0.3048)
			(stroke
				(width 0.1)
				(type default)
			)
			(layer "F.Fab")
		)
		(fp_line
			(start -0.12065 0.2794)
			(end -0.12065 0.3048)
			(stroke
				(width 0.1)
				(type default)
			)
			(layer "F.Fab")
		)
		(fp_line
			(start -0.12065 -0.2794)
			(end 0.12065 -0.2794)
			(stroke
				(width 0.1)
				(type default)
			)
			(layer "F.Fab")
		)
		(fp_line
			(start -0.12065 -0.305054)
			(end -0.12065 -0.2794)
			(stroke
				(width 0.1)
				(type default)
			)
			(layer "F.Fab")
		)
		(fp_line
			(start -0.67945 0.3048)
			(end -0.67945 -0.305054)
			(stroke
				(width 0.1)
				(type default)
			)
			(layer "F.Fab")
		)
		(fp_line
			(start -0.67945 -0.305054)
			(end -0.12065 -0.305054)
			(stroke
				(width 0.1)
				(type default)
			)
			(layer "F.Fab")
		)
		(pad "1" smd circle
			(at -0.40005 0 180)
			(size 0 0)
			(layers "F.Cu" "F.Mask" "F.Paste")
			(net "HSC_VTEMP")
		)
		(pad "2" smd circle
			(at 0.40005 0 180)
			(size 0 0)
			(layers "F.Cu" "F.Mask" "F.Paste")
			(net "AGND_HSC")
		)
	)
	(footprint ""
		(layer "F.Cu")
		(at 112.751108 -343.952322 90)
		(property "Reference" "C341"
			(at 0 0 90)
			(layer "F.SilkS")
			(hide yes)
			(effects
				(font
					(size 1.27 1.27)
				)
			)
		)
		(property "Value" ""
			(at 0 0 90)
			(layer "F.Fab")
			(effects
				(font
					(size 1.27 1.27)
				)
			)
		)
		(duplicate_pad_numbers_are_jumpers no)
		(fp_line
			(start 0.299974 -0.150114)
			(end 0.299974 0.150114)
			(stroke
				(width 0.1)
				(type default)
			)
			(layer "F.Fab")
		)
		(fp_line
			(start -0.299974 -0.150114)
			(end 0.299974 -0.150114)
			(stroke
				(width 0.1)
				(type default)
			)
			(layer "F.Fab")
		)
		(fp_line
			(start 0.299974 0.150114)
			(end -0.299974 0.150114)
			(stroke
				(width 0.1)
				(type default)
			)
			(layer "F.Fab")
		)
		(fp_line
			(start -0.299974 0.150114)
			(end -0.299974 -0.150114)
			(stroke
				(width 0.1)
				(type default)
			)
			(layer "F.Fab")
		)
		(pad "1" smd rect
			(at -0.2667 0 90)
			(size 0.3048 0.381)
			(layers "F.Cu" "F.Mask" "F.Paste")
			(net "P5E_PEX1_STN6_TX_DN<111>")
		)
		(pad "2" smd rect
			(at 0.2667 0 90)
			(size 0.3048 0.381)
			(layers "F.Cu" "F.Mask" "F.Paste")
			(net "P5E_PEX1_STN6_TX_C_DN<111>")
		)
	)
	(footprint ""
		(layer "F.Cu")
		(at 80.019398 -150.70455 180)
		(property "Reference" "C7"
			(at 0 0 180)
			(layer "F.SilkS")
			(hide yes)
			(effects
				(font
					(size 1.27 1.27)
				)
			)
		)
		(property "Value" ""
			(at 0 0 180)
			(layer "F.Fab")
			(effects
				(font
					(size 1.27 1.27)
				)
			)
		)
		(duplicate_pad_numbers_are_jumpers no)
		(fp_line
			(start 0.299974 0.150114)
			(end -0.299974 0.150114)
			(stroke
				(width 0.1)
				(type default)
			)
			(layer "F.Fab")
		)
		(fp_line
			(start 0.299974 -0.150114)
			(end 0.299974 0.150114)
			(stroke
				(width 0.1)
				(type default)
			)
			(layer "F.Fab")
		)
		(fp_line
			(start -0.299974 0.150114)
			(end -0.299974 -0.150114)
			(stroke
				(width 0.1)
				(type default)
			)
			(layer "F.Fab")
		)
		(fp_line
			(start -0.299974 -0.150114)
			(end 0.299974 -0.150114)
			(stroke
				(width 0.1)
				(type default)
			)
			(layer "F.Fab")
		)
		(pad "1" smd rect
			(at -0.2667 0 180)
			(size 0.3048 0.381)
			(layers "F.Cu" "F.Mask" "F.Paste")
			(net "P5E_PEX0_STN0_TX_DN<12>")
		)
		(pad "2" smd rect
			(at 0.2667 0 180)
			(size 0.3048 0.381)
			(layers "F.Cu" "F.Mask" "F.Paste")
			(net "P5E_PEX0_STN0_TX_C_DN<12>")
		)
	)
	(footprint ""
		(layer "F.Cu")
		(at 246.988838 -119.120666 90)
		(property "Reference" "PC905"
			(at 0 0 90)
			(layer "F.SilkS")
			(hide yes)
			(effects
				(font
					(size 1.27 1.27)
				)
			)
		)
		(property "Value" ""
			(at 0 0 90)
			(layer "F.Fab")
			(effects
				(font
					(size 1.27 1.27)
				)
			)
		)
		(duplicate_pad_numbers_are_jumpers no)
		(fp_line
			(start 0.7874 -0.4064)
			(end 0.7874 0.4064)
			(stroke
				(width 0.1524)
				(type default)
			)
			(layer "F.SilkS")
		)
		(fp_line
			(start -0.7874 -0.4064)
			(end 0.7874 -0.4064)
			(stroke
				(width 0.1524)
				(type default)
			)
			(layer "F.SilkS")
		)
		(fp_line
			(start 0.7874 0.4064)
			(end -0.7874 0.4064)
			(stroke
				(width 0.1524)
				(type default)
			)
			(layer "F.SilkS")
		)
		(fp_line
			(start -0.7874 0.4064)
			(end -0.7874 -0.4064)
			(stroke
				(width 0.1524)
				(type default)
			)
			(layer "F.SilkS")
		)
		(fp_line
			(start -0.12065 -0.305054)
			(end -0.12065 -0.2794)
			(stroke
				(width 0.1)
				(type default)
			)
			(layer "F.Fab")
		)
		(fp_line
			(start -0.67945 -0.305054)
			(end -0.12065 -0.305054)
			(stroke
				(width 0.1)
				(type default)
			)
			(layer "F.Fab")
		)
		(fp_line
			(start 0.67945 -0.3048)
			(end 0.67945 0.3048)
			(stroke
				(width 0.1)
				(type default)
			)
			(layer "F.Fab")
		)
		(fp_line
			(start 0.12065 -0.3048)
			(end 0.67945 -0.3048)
			(stroke
				(width 0.1)
				(type default)
			)
			(layer "F.Fab")
		)
		(fp_line
			(start 0.12065 -0.2794)
			(end 0.12065 -0.3048)
			(stroke
				(width 0.1)
				(type default)
			)
			(layer "F.Fab")
		)
		(fp_line
			(start -0.12065 -0.2794)
			(end 0.12065 -0.2794)
			(stroke
				(width 0.1)
				(type default)
			)
			(layer "F.Fab")
		)
		(fp_line
			(start 0.120396 0.2794)
			(end -0.12065 0.2794)
			(stroke
				(width 0.1)
				(type default)
			)
			(layer "F.Fab")
		)
		(fp_line
			(start -0.12065 0.2794)
			(end -0.12065 0.3048)
			(stroke
				(width 0.1)
				(type default)
			)
			(layer "F.Fab")
		)
		(fp_line
			(start 0.67945 0.3048)
			(end 0.120396 0.3048)
			(stroke
				(width 0.1)
				(type default)
			)
			(layer "F.Fab")
		)
		(fp_line
			(start 0.120396 0.3048)
			(end 0.120396 0.2794)
			(stroke
				(width 0.1)
				(type default)
			)
			(layer "F.Fab")
		)
		(fp_line
			(start -0.12065 0.3048)
			(end -0.67945 0.3048)
			(stroke
				(width 0.1)
				(type default)
			)
			(layer "F.Fab")
		)
		(fp_line
			(start -0.67945 0.3048)
			(end -0.67945 -0.305054)
			(stroke
				(width 0.1)
				(type default)
			)
			(layer "F.Fab")
		)
		(pad "1" smd circle
			(at -0.40005 0 90)
			(size 0 0)
			(layers "F.Cu" "F.Mask" "F.Paste")
			(net "P3V3_NIC4_CO_DV_DT")
		)
		(pad "2" smd circle
			(at 0.40005 0 90)
			(size 0 0)
			(layers "F.Cu" "F.Mask" "F.Paste")
			(net "GND")
		)
	)
	(footprint ""
		(layer "F.Cu")
		(at 279.489916 -72.766682 90)
		(property "Reference" "PR7078"
			(at 0 0 90)
			(layer "F.SilkS")
			(hide yes)
			(effects
				(font
					(size 1.27 1.27)
				)
			)
		)
		(property "Value" ""
			(at 0 0 90)
			(layer "F.Fab")
			(effects
				(font
					(size 1.27 1.27)
				)
			)
		)
		(duplicate_pad_numbers_are_jumpers no)
		(fp_line
			(start 0.7874 -0.4064)
			(end 0.7874 0.4064)
			(stroke
				(width 0.1524)
				(type default)
			)
			(layer "F.SilkS")
		)
		(fp_line
			(start -0.7874 -0.4064)
			(end 0.7874 -0.4064)
			(stroke
				(width 0.1524)
				(type default)
			)
			(layer "F.SilkS")
		)
		(fp_line
			(start 0.7874 0.4064)
			(end -0.7874 0.4064)
			(stroke
				(width 0.1524)
				(type default)
			)
			(layer "F.SilkS")
		)
		(fp_line
			(start -0.7874 0.4064)
			(end -0.7874 -0.4064)
			(stroke
				(width 0.1524)
				(type default)
			)
			(layer "F.SilkS")
		)
		(fp_line
			(start -0.12065 -0.305054)
			(end -0.12065 -0.2794)
			(stroke
				(width 0.1)
				(type default)
			)
			(layer "F.Fab")
		)
		(fp_line
			(start -0.67945 -0.305054)
			(end -0.12065 -0.305054)
			(stroke
				(width 0.1)
				(type default)
			)
			(layer "F.Fab")
		)
		(fp_line
			(start 0.67945 -0.3048)
			(end 0.67945 0.3048)
			(stroke
				(width 0.1)
				(type default)
			)
			(layer "F.Fab")
		)
		(fp_line
			(start 0.12065 -0.3048)
			(end 0.67945 -0.3048)
			(stroke
				(width 0.1)
				(type default)
			)
			(layer "F.Fab")
		)
		(fp_line
			(start 0.12065 -0.2794)
			(end 0.12065 -0.3048)
			(stroke
				(width 0.1)
				(type default)
			)
			(layer "F.Fab")
		)
		(fp_line
			(start -0.12065 -0.2794)
			(end 0.12065 -0.2794)
			(stroke
				(width 0.1)
				(type default)
			)
			(layer "F.Fab")
		)
		(fp_line
			(start 0.120396 0.2794)
			(end -0.12065 0.2794)
			(stroke
				(width 0.1)
				(type default)
			)
			(layer "F.Fab")
		)
		(fp_line
			(start -0.12065 0.2794)
			(end -0.12065 0.3048)
			(stroke
				(width 0.1)
				(type default)
			)
			(layer "F.Fab")
		)
		(fp_line
			(start 0.67945 0.3048)
			(end 0.120396 0.3048)
			(stroke
				(width 0.1)
				(type default)
			)
			(layer "F.Fab")
		)
		(fp_line
			(start 0.120396 0.3048)
			(end 0.120396 0.2794)
			(stroke
				(width 0.1)
				(type default)
			)
			(layer "F.Fab")
		)
		(fp_line
			(start -0.12065 0.3048)
			(end -0.67945 0.3048)
			(stroke
				(width 0.1)
				(type default)
			)
			(layer "F.Fab")
		)
		(fp_line
			(start -0.67945 0.3048)
			(end -0.67945 -0.305054)
			(stroke
				(width 0.1)
				(type default)
			)
			(layer "F.Fab")
		)
		(pad "1" smd circle
			(at -0.40005 0 90)
			(size 0 0)
			(layers "F.Cu" "F.Mask" "F.Paste")
			(net "P12V_SSD9_CO_ILIMIT")
		)
		(pad "2" smd circle
			(at 0.40005 0 90)
			(size 0 0)
			(layers "F.Cu" "F.Mask" "F.Paste")
			(net "GND")
		)
	)
	(footprint ""
		(layer "F.Cu")
		(at 32.470344 -250.070874 -90)
		(property "Reference" "R1160"
			(at 0 0 270)
			(layer "F.SilkS")
			(hide yes)
			(effects
				(font
					(size 1.27 1.27)
				)
			)
		)
		(property "Value" ""
			(at 0 0 270)
			(layer "F.Fab")
			(effects
				(font
					(size 1.27 1.27)
				)
			)
		)
		(duplicate_pad_numbers_are_jumpers no)
		(fp_line
			(start -0.7874 0.4064)
			(end -0.7874 -0.4064)
			(stroke
				(width 0.1524)
				(type default)
			)
			(layer "F.SilkS")
		)
		(fp_line
			(start 0.7874 0.4064)
			(end -0.7874 0.4064)
			(stroke
				(width 0.1524)
				(type default)
			)
			(layer "F.SilkS")
		)
		(fp_line
			(start -0.7874 -0.4064)
			(end 0.7874 -0.4064)
			(stroke
				(width 0.1524)
				(type default)
			)
			(layer "F.SilkS")
		)
		(fp_line
			(start 0.7874 -0.4064)
			(end 0.7874 0.4064)
			(stroke
				(width 0.1524)
				(type default)
			)
			(layer "F.SilkS")
		)
		(fp_line
			(start -0.67945 0.3048)
			(end -0.67945 -0.305054)
			(stroke
				(width 0.1)
				(type default)
			)
			(layer "F.Fab")
		)
		(fp_line
			(start -0.12065 0.3048)
			(end -0.67945 0.3048)
			(stroke
				(width 0.1)
				(type default)
			)
			(layer "F.Fab")
		)
		(fp_line
			(start 0.120396 0.3048)
			(end 0.120396 0.2794)
			(stroke
				(width 0.1)
				(type default)
			)
			(layer "F.Fab")
		)
		(fp_line
			(start 0.67945 0.3048)
			(end 0.120396 0.3048)
			(stroke
				(width 0.1)
				(type default)
			)
			(layer "F.Fab")
		)
		(fp_line
			(start -0.12065 0.2794)
			(end -0.12065 0.3048)
			(stroke
				(width 0.1)
				(type default)
			)
			(layer "F.Fab")
		)
		(fp_line
			(start 0.120396 0.2794)
			(end -0.12065 0.2794)
			(stroke
				(width 0.1)
				(type default)
			)
			(layer "F.Fab")
		)
		(fp_line
			(start -0.12065 -0.2794)
			(end 0.12065 -0.2794)
			(stroke
				(width 0.1)
				(type default)
			)
			(layer "F.Fab")
		)
		(fp_line
			(start 0.12065 -0.2794)
			(end 0.12065 -0.3048)
			(stroke
				(width 0.1)
				(type default)
			)
			(layer "F.Fab")
		)
		(fp_line
			(start 0.12065 -0.3048)
			(end 0.67945 -0.3048)
			(stroke
				(width 0.1)
				(type default)
			)
			(layer "F.Fab")
		)
		(fp_line
			(start 0.67945 -0.3048)
			(end 0.67945 0.3048)
			(stroke
				(width 0.1)
				(type default)
			)
			(layer "F.Fab")
		)
		(fp_line
			(start -0.67945 -0.305054)
			(end -0.12065 -0.305054)
			(stroke
				(width 0.1)
				(type default)
			)
			(layer "F.Fab")
		)
		(fp_line
			(start -0.12065 -0.305054)
			(end -0.12065 -0.2794)
			(stroke
				(width 0.1)
				(type default)
			)
			(layer "F.Fab")
		)
		(pad "1" smd circle
			(at -0.40005 0 270)
			(size 0 0)
			(layers "F.Cu" "F.Mask" "F.Paste")
			(net "PEX0_MODE_SEL8")
		)
		(pad "2" smd circle
			(at 0.40005 0 270)
			(size 0 0)
			(layers "F.Cu" "F.Mask" "F.Paste")
			(net "P1V8_PEX")
		)
	)
	(footprint ""
		(layer "F.Cu")
		(at 148.517102 -308.852062 -135)
		(property "Reference" "R1326"
			(at 0 0 225)
			(layer "F.SilkS")
			(hide yes)
			(effects
				(font
					(size 1.27 1.27)
				)
			)
		)
		(property "Value" ""
			(at 0 0 225)
			(layer "F.Fab")
			(effects
				(font
					(size 1.27 1.27)
				)
			)
		)
		(duplicate_pad_numbers_are_jumpers no)
		(fp_line
			(start 0.787389 0.406267)
			(end -0.787389 0.406267)
			(stroke
				(width 0.1524)
				(type default)
			)
			(layer "F.SilkS")
		)
		(fp_line
			(start 0.787389 -0.406267)
			(end 0.787389 0.406267)
			(stroke
				(width 0.1524)
				(type default)
			)
			(layer "F.SilkS")
		)
		(fp_line
			(start -0.787389 0.406267)
			(end -0.787389 -0.406267)
			(stroke
				(width 0.1524)
				(type default)
			)
			(layer "F.SilkS")
		)
		(fp_line
			(start -0.787389 -0.406267)
			(end 0.787389 -0.406267)
			(stroke
				(width 0.1524)
				(type default)
			)
			(layer "F.SilkS")
		)
		(fp_line
			(start 0.679446 0.30479)
			(end 0.120515 0.30479)
			(stroke
				(width 0.1)
				(type default)
			)
			(layer "F.Fab")
		)
		(fp_line
			(start 0.120515 0.30479)
			(end 0.120335 0.279466)
			(stroke
				(width 0.1)
				(type default)
			)
			(layer "F.Fab")
		)
		(fp_line
			(start 0.120335 0.279466)
			(end -0.120695 0.279466)
			(stroke
				(width 0.1)
				(type default)
			)
			(layer "F.Fab")
		)
		(fp_line
			(start 0.679446 -0.30479)
			(end 0.679446 0.30479)
			(stroke
				(width 0.1)
				(type default)
			)
			(layer "F.Fab")
		)
		(fp_line
			(start -0.120515 0.30479)
			(end -0.679446 0.30479)
			(stroke
				(width 0.1)
				(type default)
			)
			(layer "F.Fab")
		)
		(fp_line
			(start -0.120695 0.279466)
			(end -0.120515 0.30479)
			(stroke
				(width 0.1)
				(type default)
			)
			(layer "F.Fab")
		)
		(fp_line
			(start 0.120695 -0.279466)
			(end 0.120515 -0.30479)
			(stroke
				(width 0.1)
				(type default)
			)
			(layer "F.Fab")
		)
		(fp_line
			(start 0.120515 -0.30479)
			(end 0.679446 -0.30479)
			(stroke
				(width 0.1)
				(type default)
			)
			(layer "F.Fab")
		)
		(fp_line
			(start -0.679446 0.30479)
			(end -0.679446 -0.305149)
			(stroke
				(width 0.1)
				(type default)
			)
			(layer "F.Fab")
		)
		(fp_line
			(start -0.120695 -0.279466)
			(end 0.120695 -0.279466)
			(stroke
				(width 0.1)
				(type default)
			)
			(layer "F.Fab")
		)
		(fp_line
			(start -0.120695 -0.304969)
			(end -0.120695 -0.279466)
			(stroke
				(width 0.1)
				(type default)
			)
			(layer "F.Fab")
		)
		(fp_line
			(start -0.679446 -0.305149)
			(end -0.120695 -0.304969)
			(stroke
				(width 0.1)
				(type default)
			)
			(layer "F.Fab")
		)
		(pad "1" smd circle
			(at -0.40005 0 225)
			(size 0 0)
			(layers "F.Cu" "F.Mask" "F.Paste")
			(net "PU_PEX1_ATPG_MODE_L")
		)
		(pad "2" smd circle
			(at 0.40005 0 225)
			(size 0 0)
			(layers "F.Cu" "F.Mask" "F.Paste")
			(net "P1V8_PEX")
		)
	)
)
